(kicad_pcb
	(version 20260206)
	(generator "pcbnew")
	(generator_version "10.0")
	(general
		(thickness 1.6)
		(legacy_teardrops no)
	)
	(paper "A4")
	(title_block
		(title "Wiwynn_Tioga_Pass_MB.brd")
		(comment 1 "Tioga Pass / footprints 3107-3113 of 4770")
	)
	(layers
		(0 "F.Cu" signal "TOP")
		(4 "In1.Cu" signal "L2GND")
		(6 "In2.Cu" signal "L3")
		(8 "In3.Cu" signal "L4GND")
		(10 "In4.Cu" signal "L5")
		(12 "In5.Cu" signal "L6GND")
		(14 "In6.Cu" signal "L7VCC")
		(16 "In7.Cu" signal "L8VCC")
		(18 "In8.Cu" signal "L9GND")
		(20 "In9.Cu" signal "L10")
		(22 "In10.Cu" signal "L11GND")
		(24 "In11.Cu" signal "L12")
		(26 "In12.Cu" signal "L13GND")
		(2 "B.Cu" signal "BOTTOM")
		(9 "F.Adhes" user "F.Adhesive")
		(11 "B.Adhes" user "B.Adhesive")
		(13 "F.Paste" user "Package Geometry/Pastemask Top")
		(15 "B.Paste" user "Package Geometry/Pastemask Bottom")
		(5 "F.SilkS" user "Ref Des/Silkscreen Top")
		(7 "B.SilkS" user "Ref Des/Silkscreen Bottom")
		(1 "F.Mask" user "Board Geometry/Soldermask Top")
		(3 "B.Mask" user "Board Geometry/Soldermask Bottom")
		(17 "Dwgs.User" user "User.Drawings")
		(19 "Cmts.User" user "User.Comments")
		(21 "Eco1.User" user "User.Eco1")
		(23 "Eco2.User" user "User.Eco2")
		(25 "Edge.Cuts" user "Board Geometry/Outline")
		(27 "Margin" user)
		(31 "F.CrtYd" user "Package Geometry/Place Bound Top")
		(29 "B.CrtYd" user "Package Geometry/Place Bound Bottom")
		(35 "F.Fab" user "Ref Des/Assembly Top")
		(33 "B.Fab" user "Ref Des/Assembly Bottom")
	)
	(footprint ""
		(layer "B.Cu")
		(at 22.57298 -74.42708 90)
		(property "Reference" "C9P15"
			(at 0 0 90)
			(layer "B.SilkS")
			(hide yes)
			(effects
				(font
					(size 1.27 1.27)
				)
				(justify mirror)
			)
		)
		(property "Value" ""
			(at 0 0 90)
			(layer "B.Fab")
			(effects
				(font
					(size 1.27 1.27)
				)
				(justify mirror)
			)
		)
		(duplicate_pad_numbers_are_jumpers no)
		(fp_poly
			(pts
				(xy -0.3048 -0.1016) (xy -0.3048 0.9906) (xy 0.3048 0.9906) (xy 0.3048 -0.1016)
			)
			(stroke
				(width 0)
				(type default)
			)
			(fill no)
			(layer "B.CrtYd")
		)
		(fp_line
			(start 0.3048 -0.1016)
			(end 0.3048 0.9906)
			(stroke
				(width 0.1)
				(type default)
			)
			(layer "B.Fab")
		)
		(fp_line
			(start -0.3048 -0.1016)
			(end 0.3048 -0.1016)
			(stroke
				(width 0.1)
				(type default)
			)
			(layer "B.Fab")
		)
		(fp_line
			(start 0.3048 0.9906)
			(end -0.3048 0.9906)
			(stroke
				(width 0.1)
				(type default)
			)
			(layer "B.Fab")
		)
		(fp_line
			(start -0.3048 0.9906)
			(end -0.3048 -0.1016)
			(stroke
				(width 0.1)
				(type default)
			)
			(layer "B.Fab")
		)
		(pad "1" smd rect
			(at 0 0 270)
			(size 0.508 0.508)
			(layers "B.Cu" "B.Mask" "B.Paste")
			(net "A_HSC_ISET")
		)
		(pad "2" smd rect
			(at 0 0.889 270)
			(size 0.508 0.508)
			(layers "B.Cu" "B.Mask" "B.Paste")
			(net "AGND_HSC")
		)
		(zone
			(layer "B.Cu")
			(hatch none 0.5)
			(connect_pads
				(clearance 0)
			)
			(min_thickness 0.25)
			(keepout
				(tracks allowed)
				(vias not_allowed)
				(pads allowed)
				(copperpour not_allowed)
				(footprints allowed)
			)
			(placement
				(enabled no)
				(sheetname "")
			)
			(fill
				(thermal_gap 0.5)
				(thermal_bridge_width 0.5)
				(island_removal_mode 0)
			)
			(polygon
				(pts
					(xy 22.82698 -74.68108) (xy 22.82698 -74.17308) (xy 23.20798 -74.17308) (xy 23.20798 -74.68108)
				)
			)
		)
		(zone
			(layer "B.Cu")
			(hatch none 0.5)
			(connect_pads
				(clearance 0)
			)
			(min_thickness 0.25)
			(keepout
				(tracks not_allowed)
				(vias allowed)
				(pads allowed)
				(copperpour not_allowed)
				(footprints allowed)
			)
			(placement
				(enabled no)
				(sheetname "")
			)
			(fill
				(thermal_gap 0.5)
				(thermal_bridge_width 0.5)
				(island_removal_mode 0)
			)
			(polygon
				(pts
					(xy 23.20798 -74.68108) (xy 23.20798 -74.17308) (xy 22.82698 -74.17308) (xy 22.82698 -74.68108)
				)
			)
		)
	)
	(footprint ""
		(layer "B.Cu")
		(at 30.952948 -96.7994)
		(property "Reference" "CT55"
			(at 0.8382 -0.84963 0)
			(unlocked yes)
			(layer "B.SilkS")
			(effects
				(font
					(size 0.7874 0.5842)
					(thickness 0.1524)
				)
				(justify left mirror)
			)
		)
		(property "Value" ""
			(at 0 0 0)
			(layer "B.Fab")
			(effects
				(font
					(size 1.27 1.27)
				)
				(justify mirror)
			)
		)
		(duplicate_pad_numbers_are_jumpers no)
		(fp_poly
			(pts
				(xy -0.3048 -0.1016) (xy -0.3048 0.9906) (xy 0.3048 0.9906) (xy 0.3048 -0.1016)
			)
			(stroke
				(width 0)
				(type default)
			)
			(fill no)
			(layer "B.CrtYd")
		)
		(fp_line
			(start -0.3048 -0.1016)
			(end 0.3048 -0.1016)
			(stroke
				(width 0.1)
				(type default)
			)
			(layer "B.Fab")
		)
		(fp_line
			(start -0.3048 0.9906)
			(end -0.3048 -0.1016)
			(stroke
				(width 0.1)
				(type default)
			)
			(layer "B.Fab")
		)
		(fp_line
			(start 0.3048 -0.1016)
			(end 0.3048 0.9906)
			(stroke
				(width 0.1)
				(type default)
			)
			(layer "B.Fab")
		)
		(fp_line
			(start 0.3048 0.9906)
			(end -0.3048 0.9906)
			(stroke
				(width 0.1)
				(type default)
			)
			(layer "B.Fab")
		)
		(pad "1" smd rect
			(at 0 0 180)
			(size 0.508 0.508)
			(layers "B.Cu" "B.Mask" "B.Paste")
			(net "A_TSENSE_PVSA_CPU1")
		)
		(pad "2" smd rect
			(at 0 0.889 180)
			(size 0.508 0.508)
			(layers "B.Cu" "B.Mask" "B.Paste")
			(net "GND")
		)
		(zone
			(layer "B.Cu")
			(hatch none 0.5)
			(connect_pads
				(clearance 0)
			)
			(min_thickness 0.25)
			(keepout
				(tracks allowed)
				(vias not_allowed)
				(pads allowed)
				(copperpour not_allowed)
				(footprints allowed)
			)
			(placement
				(enabled no)
				(sheetname "")
			)
			(fill
				(thermal_gap 0.5)
				(thermal_bridge_width 0.5)
				(island_removal_mode 0)
			)
			(polygon
				(pts
					(xy 31.206948 -96.5454) (xy 30.698948 -96.5454) (xy 30.698948 -96.1644) (xy 31.206948 -96.1644)
				)
			)
		)
		(zone
			(layer "B.Cu")
			(hatch none 0.5)
			(connect_pads
				(clearance 0)
			)
			(min_thickness 0.25)
			(keepout
				(tracks not_allowed)
				(vias allowed)
				(pads allowed)
				(copperpour not_allowed)
				(footprints allowed)
			)
			(placement
				(enabled no)
				(sheetname "")
			)
			(fill
				(thermal_gap 0.5)
				(thermal_bridge_width 0.5)
				(island_removal_mode 0)
			)
			(polygon
				(pts
					(xy 31.206948 -96.1644) (xy 30.698948 -96.1644) (xy 30.698948 -96.5454) (xy 31.206948 -96.5454)
				)
			)
		)
	)
	(footprint ""
		(layer "B.Cu")
		(at 393.4079 -20.6248 90)
		(property "Reference" "R32W2"
			(at 0.8382 -0.67818 90)
			(unlocked yes)
			(layer "B.SilkS")
			(effects
				(font
					(size 0.4064 0.254)
					(thickness 0.1524)
				)
				(justify left mirror)
			)
		)
		(property "Value" ""
			(at 0 0 90)
			(layer "B.Fab")
			(effects
				(font
					(size 1.27 1.27)
				)
				(justify mirror)
			)
		)
		(duplicate_pad_numbers_are_jumpers no)
		(fp_poly
			(pts
				(xy 0.2794 -0.1016) (xy -0.2794 -0.1016) (xy -0.2794 0.9906) (xy 0.2794 0.9906)
			)
			(stroke
				(width 0)
				(type default)
			)
			(fill no)
			(layer "B.CrtYd")
		)
		(fp_line
			(start 0.2794 -0.1016)
			(end 0.2794 0.9906)
			(stroke
				(width 0.1)
				(type default)
			)
			(layer "B.Fab")
		)
		(fp_line
			(start -0.2794 -0.1016)
			(end 0.2794 -0.1016)
			(stroke
				(width 0.1)
				(type default)
			)
			(layer "B.Fab")
		)
		(fp_line
			(start 0.2794 0.9906)
			(end -0.2794 0.9906)
			(stroke
				(width 0.1)
				(type default)
			)
			(layer "B.Fab")
		)
		(fp_line
			(start -0.2794 0.9906)
			(end -0.2794 -0.1016)
			(stroke
				(width 0.1)
				(type default)
			)
			(layer "B.Fab")
		)
		(pad "1" smd rect
			(at 0 0 270)
			(size 0.508 0.508)
			(layers "B.Cu" "B.Mask" "B.Paste")
			(net "P1V8_M2")
		)
		(pad "2" smd rect
			(at 0 0.889 270)
			(size 0.508 0.508)
			(layers "B.Cu" "B.Mask" "B.Paste")
			(net "VREF_LMV431_1V42")
		)
		(zone
			(layer "B.Cu")
			(hatch none 0.5)
			(connect_pads
				(clearance 0)
			)
			(min_thickness 0.25)
			(keepout
				(tracks allowed)
				(vias not_allowed)
				(pads allowed)
				(copperpour not_allowed)
				(footprints allowed)
			)
			(placement
				(enabled no)
				(sheetname "")
			)
			(fill
				(thermal_gap 0.5)
				(thermal_bridge_width 0.5)
				(island_removal_mode 0)
			)
			(polygon
				(pts
					(xy 393.6619 -20.8788) (xy 393.6619 -20.3708) (xy 394.0429 -20.3708) (xy 394.0429 -20.8788)
				)
			)
		)
		(zone
			(layer "B.Cu")
			(hatch none 0.5)
			(connect_pads
				(clearance 0)
			)
			(min_thickness 0.25)
			(keepout
				(tracks not_allowed)
				(vias allowed)
				(pads allowed)
				(copperpour not_allowed)
				(footprints allowed)
			)
			(placement
				(enabled no)
				(sheetname "")
			)
			(fill
				(thermal_gap 0.5)
				(thermal_bridge_width 0.5)
				(island_removal_mode 0)
			)
			(polygon
				(pts
					(xy 394.0429 -20.8788) (xy 394.0429 -20.3708) (xy 393.6619 -20.3708) (xy 393.6619 -20.8788)
				)
			)
		)
	)
	(footprint ""
		(layer "B.Cu")
		(at 379.222 -87.3125 180)
		(property "Reference" "R7D5"
			(at 0 0 0)
			(layer "B.SilkS")
			(hide yes)
			(effects
				(font
					(size 1.27 1.27)
				)
				(justify mirror)
			)
		)
		(property "Value" ""
			(at 0 0 0)
			(layer "B.Fab")
			(effects
				(font
					(size 1.27 1.27)
				)
				(justify mirror)
			)
		)
		(duplicate_pad_numbers_are_jumpers no)
		(fp_poly
			(pts
				(xy 0.2794 -0.1016) (xy -0.2794 -0.1016) (xy -0.2794 0.9906) (xy 0.2794 0.9906)
			)
			(stroke
				(width 0)
				(type default)
			)
			(fill no)
			(layer "B.CrtYd")
		)
		(fp_line
			(start 0.2794 0.9906)
			(end -0.2794 0.9906)
			(stroke
				(width 0.1)
				(type default)
			)
			(layer "B.Fab")
		)
		(fp_line
			(start 0.2794 -0.1016)
			(end 0.2794 0.9906)
			(stroke
				(width 0.1)
				(type default)
			)
			(layer "B.Fab")
		)
		(fp_line
			(start -0.2794 0.9906)
			(end -0.2794 -0.1016)
			(stroke
				(width 0.1)
				(type default)
			)
			(layer "B.Fab")
		)
		(fp_line
			(start -0.2794 -0.1016)
			(end 0.2794 -0.1016)
			(stroke
				(width 0.1)
				(type default)
			)
			(layer "B.Fab")
		)
		(pad "1" smd rect
			(at 0 0)
			(size 0.508 0.508)
			(layers "B.Cu" "B.Mask" "B.Paste")
			(net "P3V3_STBY")
		)
		(pad "2" smd rect
			(at 0 0.889)
			(size 0.508 0.508)
			(layers "B.Cu" "B.Mask" "B.Paste")
			(net "FM_MB_SLOT_ID0")
		)
		(zone
			(layer "B.Cu")
			(hatch none 0.5)
			(connect_pads
				(clearance 0)
			)
			(min_thickness 0.25)
			(keepout
				(tracks not_allowed)
				(vias allowed)
				(pads allowed)
				(copperpour not_allowed)
				(footprints allowed)
			)
			(placement
				(enabled no)
				(sheetname "")
			)
			(fill
				(thermal_gap 0.5)
				(thermal_bridge_width 0.5)
				(island_removal_mode 0)
			)
			(polygon
				(pts
					(xy 378.968 -87.9475) (xy 379.476 -87.9475) (xy 379.476 -87.5665) (xy 378.968 -87.5665)
				)
			)
		)
		(zone
			(layer "B.Cu")
			(hatch none 0.5)
			(connect_pads
				(clearance 0)
			)
			(min_thickness 0.25)
			(keepout
				(tracks allowed)
				(vias not_allowed)
				(pads allowed)
				(copperpour not_allowed)
				(footprints allowed)
			)
			(placement
				(enabled no)
				(sheetname "")
			)
			(fill
				(thermal_gap 0.5)
				(thermal_bridge_width 0.5)
				(island_removal_mode 0)
			)
			(polygon
				(pts
					(xy 378.968 -87.5665) (xy 379.476 -87.5665) (xy 379.476 -87.9475) (xy 378.968 -87.9475)
				)
			)
		)
	)
	(footprint ""
		(layer "B.Cu")
		(at 445.02324 -24.28494)
		(property "Reference" "C25W1"
			(at 0.8382 -0.67818 0)
			(unlocked yes)
			(layer "B.SilkS")
			(effects
				(font
					(size 0.4064 0.254)
					(thickness 0.1524)
				)
				(justify left mirror)
			)
		)
		(property "Value" ""
			(at 0 0 0)
			(layer "B.Fab")
			(effects
				(font
					(size 1.27 1.27)
				)
				(justify mirror)
			)
		)
		(duplicate_pad_numbers_are_jumpers no)
		(fp_poly
			(pts
				(xy -0.3048 -0.1016) (xy -0.3048 0.9906) (xy 0.3048 0.9906) (xy 0.3048 -0.1016)
			)
			(stroke
				(width 0)
				(type default)
			)
			(fill no)
			(layer "B.CrtYd")
		)
		(fp_line
			(start -0.3048 -0.1016)
			(end 0.3048 -0.1016)
			(stroke
				(width 0.1)
				(type default)
			)
			(layer "B.Fab")
		)
		(fp_line
			(start -0.3048 0.9906)
			(end -0.3048 -0.1016)
			(stroke
				(width 0.1)
				(type default)
			)
			(layer "B.Fab")
		)
		(fp_line
			(start 0.3048 -0.1016)
			(end 0.3048 0.9906)
			(stroke
				(width 0.1)
				(type default)
			)
			(layer "B.Fab")
		)
		(fp_line
			(start 0.3048 0.9906)
			(end -0.3048 0.9906)
			(stroke
				(width 0.1)
				(type default)
			)
			(layer "B.Fab")
		)
		(pad "1" smd rect
			(at 0 0 180)
			(size 0.508 0.508)
			(layers "B.Cu" "B.Mask" "B.Paste")
			(net "P1V2_AUX_BMC")
		)
		(pad "2" smd rect
			(at 0 0.889 180)
			(size 0.508 0.508)
			(layers "B.Cu" "B.Mask" "B.Paste")
			(net "GND")
		)
		(zone
			(layer "B.Cu")
			(hatch none 0.5)
			(connect_pads
				(clearance 0)
			)
			(min_thickness 0.25)
			(keepout
				(tracks allowed)
				(vias not_allowed)
				(pads allowed)
				(copperpour not_allowed)
				(footprints allowed)
			)
			(placement
				(enabled no)
				(sheetname "")
			)
			(fill
				(thermal_gap 0.5)
				(thermal_bridge_width 0.5)
				(island_removal_mode 0)
			)
			(polygon
				(pts
					(xy 445.27724 -24.03094) (xy 444.76924 -24.03094) (xy 444.76924 -23.64994) (xy 445.27724 -23.64994)
				)
			)
		)
		(zone
			(layer "B.Cu")
			(hatch none 0.5)
			(connect_pads
				(clearance 0)
			)
			(min_thickness 0.25)
			(keepout
				(tracks not_allowed)
				(vias allowed)
				(pads allowed)
				(copperpour not_allowed)
				(footprints allowed)
			)
			(placement
				(enabled no)
				(sheetname "")
			)
			(fill
				(thermal_gap 0.5)
				(thermal_bridge_width 0.5)
				(island_removal_mode 0)
			)
			(polygon
				(pts
					(xy 445.27724 -23.64994) (xy 444.76924 -23.64994) (xy 444.76924 -24.03094) (xy 445.27724 -24.03094)
				)
			)
		)
	)
	(footprint ""
		(layer "B.Cu")
		(at 413.639 -121.92 180)
		(property "Reference" "C8B15"
			(at 0 0 0)
			(layer "B.SilkS")
			(hide yes)
			(effects
				(font
					(size 1.27 1.27)
				)
				(justify mirror)
			)
		)
		(property "Value" ""
			(at 0 0 0)
			(layer "B.Fab")
			(effects
				(font
					(size 1.27 1.27)
				)
				(justify mirror)
			)
		)
		(duplicate_pad_numbers_are_jumpers no)
		(fp_poly
			(pts
				(xy 0.7239 -0.2159) (xy -0.7239 -0.2159) (xy -0.7239 1.9939) (xy 0.7239 1.9939)
			)
			(stroke
				(width 0)
				(type default)
			)
			(fill no)
			(layer "B.CrtYd")
		)
		(fp_line
			(start 0.7239 1.9939)
			(end -0.7239 1.9939)
			(stroke
				(width 0.1)
				(type default)
			)
			(layer "B.Fab")
		)
		(fp_line
			(start 0.7239 -0.2159)
			(end 0.7239 1.9939)
			(stroke
				(width 0.1)
				(type default)
			)
			(layer "B.Fab")
		)
		(fp_line
			(start -0.7239 1.9939)
			(end -0.7239 -0.2159)
			(stroke
				(width 0.1)
				(type default)
			)
			(layer "B.Fab")
		)
		(fp_line
			(start -0.7239 -0.2159)
			(end 0.7239 -0.2159)
			(stroke
				(width 0.1)
				(type default)
			)
			(layer "B.Fab")
		)
		(pad "1" smd rect
			(at 0 0)
			(size 1.27 1.016)
			(layers "B.Cu" "B.Mask" "B.Paste")
			(net "P1V05_PCH_STBY")
		)
		(pad "2" smd rect
			(at 0 1.778)
			(size 1.27 1.016)
			(layers "B.Cu" "B.Mask" "B.Paste")
			(net "GND")
		)
		(zone
			(layer "B.Cu")
			(hatch none 0.5)
			(connect_pads
				(clearance 0)
			)
			(min_thickness 0.25)
			(keepout
				(tracks not_allowed)
				(vias allowed)
				(pads allowed)
				(copperpour not_allowed)
				(footprints allowed)
			)
			(placement
				(enabled no)
				(sheetname "")
			)
			(fill
				(thermal_gap 0.5)
				(thermal_bridge_width 0.5)
				(island_removal_mode 0)
			)
			(polygon
				(pts
					(xy 413.004 -122.428) (xy 414.274 -122.428) (xy 414.274 -123.19) (xy 413.004 -123.19)
				)
			)
		)
	)
	(footprint ""
		(layer "B.Cu")
		(at 375.0945 -45.72 90)
		(property "Reference" "R2T39"
			(at 0 0 90)
			(layer "B.SilkS")
			(hide yes)
			(effects
				(font
					(size 1.27 1.27)
				)
				(justify mirror)
			)
		)
		(property "Value" ""
			(at 0 0 90)
			(layer "B.Fab")
			(effects
				(font
					(size 1.27 1.27)
				)
				(justify mirror)
			)
		)
		(duplicate_pad_numbers_are_jumpers no)
		(fp_poly
			(pts
				(xy 0.2794 -0.1016) (xy -0.2794 -0.1016) (xy -0.2794 0.9906) (xy 0.2794 0.9906)
			)
			(stroke
				(width 0)
				(type default)
			)
			(fill no)
			(layer "B.CrtYd")
		)
		(fp_line
			(start 0.2794 -0.1016)
			(end 0.2794 0.9906)
			(stroke
				(width 0.1)
				(type default)
			)
			(layer "B.Fab")
		)
		(fp_line
			(start -0.2794 -0.1016)
			(end 0.2794 -0.1016)
			(stroke
				(width 0.1)
				(type default)
			)
			(layer "B.Fab")
		)
		(fp_line
			(start 0.2794 0.9906)
			(end -0.2794 0.9906)
			(stroke
				(width 0.1)
				(type default)
			)
			(layer "B.Fab")
		)
		(fp_line
			(start -0.2794 0.9906)
			(end -0.2794 -0.1016)
			(stroke
				(width 0.1)
				(type default)
			)
			(layer "B.Fab")
		)
		(pad "1" smd rect
			(at 0 0 270)
			(size 0.508 0.508)
			(layers "B.Cu" "B.Mask" "B.Paste")
			(net "P0V7_GTL2104_5_VREF")
		)
		(pad "2" smd rect
			(at 0 0.889 270)
			(size 0.508 0.508)
			(layers "B.Cu" "B.Mask" "B.Paste")
			(net "GND")
		)
		(zone
			(layer "B.Cu")
			(hatch none 0.5)
			(connect_pads
				(clearance 0)
			)
			(min_thickness 0.25)
			(keepout
				(tracks allowed)
				(vias not_allowed)
				(pads allowed)
				(copperpour not_allowed)
				(footprints allowed)
			)
			(placement
				(enabled no)
				(sheetname "")
			)
			(fill
				(thermal_gap 0.5)
				(thermal_bridge_width 0.5)
				(island_removal_mode 0)
			)
			(polygon
				(pts
					(xy 375.3485 -45.974) (xy 375.3485 -45.466) (xy 375.7295 -45.466) (xy 375.7295 -45.974)
				)
			)
		)
		(zone
			(layer "B.Cu")
			(hatch none 0.5)
			(connect_pads
				(clearance 0)
			)
			(min_thickness 0.25)
			(keepout
				(tracks not_allowed)
				(vias allowed)
				(pads allowed)
				(copperpour not_allowed)
				(footprints allowed)
			)
			(placement
				(enabled no)
				(sheetname "")
			)
			(fill
				(thermal_gap 0.5)
				(thermal_bridge_width 0.5)
				(island_removal_mode 0)
			)
			(polygon
				(pts
					(xy 375.7295 -45.974) (xy 375.7295 -45.466) (xy 375.3485 -45.466) (xy 375.3485 -45.974)
				)
			)
		)
	)
)
